# T6G (Grand Teton) — schematic netlist excerpt (pin names and nets, part order shuffled) for the footprints in the layout excerpt that follows; sources: Cadence DE-HDL packaged netlist, KiCad conversion of 04192023_DAF0TMB3IC0_F0TG_MB_C_brd_V02_OCP.brd

PC255  Q_CAP  560PF 50V 10% EMPTY  pkg C0402  page 225 : A = SW_PVDD11_S3_P1_SW2 ; B = SW_PVDD11_S3_P1_SW2_RC
PC2087  Q_CAP  1UF 25V 10% X6S  pkg C0402  page 134 : A = GND ; B = P12V_OCP_REG_1

(kicad_pcb
	(version 20260206)
	(generator "pcbnew")
	(generator_version "10.0")
	(general
		(thickness 1.6)
		(legacy_teardrops no)
	)
	(paper "A4")
	(title_block
		(title "04192023_DAF0TMB3IC0_F0TG_MB_C_brd_V02_OCP.brd")
		(comment 1 "Grand Teton / footprints 1817-1818 of 8354")
	)
	(layers
		(0 "F.Cu" signal "TOP")
		(4 "In1.Cu" signal "GND")
		(6 "In2.Cu" signal "IN1")
		(8 "In3.Cu" signal "GND1")
		(10 "In4.Cu" signal "IN2")
		(12 "In5.Cu" signal "GND2")
		(14 "In6.Cu" signal "IN3")
		(16 "In7.Cu" signal "GND3")
		(18 "In8.Cu" signal "VCC")
		(20 "In9.Cu" signal "VCC1")
		(22 "In10.Cu" signal "GND4")
		(24 "In11.Cu" signal "IN4")
		(26 "In12.Cu" signal "GND5")
		(28 "In13.Cu" signal "IN5")
		(30 "In14.Cu" signal "GND6")
		(32 "In15.Cu" signal "IN6")
		(34 "In16.Cu" signal "GND7")
		(2 "B.Cu" signal "BOTTOM")
		(9 "F.Adhes" user "F.Adhesive")
		(11 "B.Adhes" user "B.Adhesive")
		(13 "F.Paste" user "Package Geometry/Pastemask Top")
		(15 "B.Paste" user "Package Geometry/Pastemask Bottom")
		(5 "F.SilkS" user "Ref Des/Silkscreen Top")
		(7 "B.SilkS" user "Ref Des/Silkscreen Bottom")
		(1 "F.Mask" user "Board Geometry/Soldermask Top")
		(3 "B.Mask" user "Board Geometry/Soldermask Bottom")
		(17 "Dwgs.User" user "User.Drawings")
		(19 "Cmts.User" user "User.Comments")
		(21 "Eco1.User" user "User.Eco1")
		(23 "Eco2.User" user "User.Eco2")
		(25 "Edge.Cuts" user "Board Geometry/Outline")
		(27 "Margin" user)
		(31 "F.CrtYd" user "Package Geometry/Place Bound Top")
		(29 "B.CrtYd" user "Package Geometry/Place Bound Bottom")
		(35 "F.Fab" user "Ref Des/Assembly Top")
		(33 "B.Fab" user "Ref Des/Assembly Bottom")
	)
	(footprint ""
		(layer "F.Cu")
		(at 447.565272 -19.506438)
		(property "Reference" "PC2087"
			(at 0 0 0)
			(layer "F.SilkS")
			(hide yes)
			(effects
				(font
					(size 1.27 1.27)
				)
			)
		)
		(property "Value" ""
			(at 0 0 0)
			(layer "F.Fab")
			(effects
				(font
					(size 1.27 1.27)
				)
			)
		)
		(duplicate_pad_numbers_are_jumpers no)
		(fp_line
			(start -0.7874 -0.4064)
			(end 0.7874 -0.4064)
			(stroke
				(width 0.1524)
				(type default)
			)
			(layer "F.SilkS")
		)
		(fp_line
			(start -0.7874 0.4064)
			(end -0.7874 -0.4064)
			(stroke
				(width 0.1524)
				(type default)
			)
			(layer "F.SilkS")
		)
		(fp_line
			(start 0.7874 -0.4064)
			(end 0.7874 0.4064)
			(stroke
				(width 0.1524)
				(type default)
			)
			(layer "F.SilkS")
		)
		(fp_line
			(start 0.7874 0.4064)
			(end -0.7874 0.4064)
			(stroke
				(width 0.1524)
				(type default)
			)
			(layer "F.SilkS")
		)
		(fp_line
			(start -0.67945 -0.305054)
			(end -0.12065 -0.305054)
			(stroke
				(width 0.1)
				(type default)
			)
			(layer "F.Fab")
		)
		(fp_line
			(start -0.67945 0.3048)
			(end -0.67945 -0.305054)
			(stroke
				(width 0.1)
				(type default)
			)
			(layer "F.Fab")
		)
		(fp_line
			(start -0.12065 -0.305054)
			(end -0.12065 -0.2794)
			(stroke
				(width 0.1)
				(type default)
			)
			(layer "F.Fab")
		)
		(fp_line
			(start -0.12065 -0.2794)
			(end 0.12065 -0.2794)
			(stroke
				(width 0.1)
				(type default)
			)
			(layer "F.Fab")
		)
		(fp_line
			(start -0.12065 0.2794)
			(end -0.12065 0.3048)
			(stroke
				(width 0.1)
				(type default)
			)
			(layer "F.Fab")
		)
		(fp_line
			(start -0.12065 0.3048)
			(end -0.67945 0.3048)
			(stroke
				(width 0.1)
				(type default)
			)
			(layer "F.Fab")
		)
		(fp_line
			(start 0.120396 0.2794)
			(end -0.12065 0.2794)
			(stroke
				(width 0.1)
				(type default)
			)
			(layer "F.Fab")
		)
		(fp_line
			(start 0.120396 0.3048)
			(end 0.120396 0.2794)
			(stroke
				(width 0.1)
				(type default)
			)
			(layer "F.Fab")
		)
		(fp_line
			(start 0.12065 -0.3048)
			(end 0.67945 -0.3048)
			(stroke
				(width 0.1)
				(type default)
			)
			(layer "F.Fab")
		)
		(fp_line
			(start 0.12065 -0.2794)
			(end 0.12065 -0.3048)
			(stroke
				(width 0.1)
				(type default)
			)
			(layer "F.Fab")
		)
		(fp_line
			(start 0.67945 -0.3048)
			(end 0.67945 0.3048)
			(stroke
				(width 0.1)
				(type default)
			)
			(layer "F.Fab")
		)
		(fp_line
			(start 0.67945 0.3048)
			(end 0.120396 0.3048)
			(stroke
				(width 0.1)
				(type default)
			)
			(layer "F.Fab")
		)
		(pad "1" smd circle
			(at -0.40005 0)
			(size 0 0)
			(layers "F.Cu" "F.Mask" "F.Paste")
			(net "GND")
		)
		(pad "2" smd circle
			(at 0.40005 0)
			(size 0 0)
			(layers "F.Cu" "F.Mask" "F.Paste")
			(net "P12V_OCP_REG_1")
		)
	)
	(footprint ""
		(layer "F.Cu")
		(at 187.552584 -348.31655 180)
		(property "Reference" "PC255"
			(at 0 0 180)
			(layer "F.SilkS")
			(hide yes)
			(effects
				(font
					(size 1.27 1.27)
				)
			)
		)
		(property "Value" ""
			(at 0 0 180)
			(layer "F.Fab")
			(effects
				(font
					(size 1.27 1.27)
				)
			)
		)
		(duplicate_pad_numbers_are_jumpers no)
		(fp_line
			(start 0.7874 0.4064)
			(end -0.7874 0.4064)
			(stroke
				(width 0.1524)
				(type default)
			)
			(layer "F.SilkS")
		)
		(fp_line
			(start 0.7874 -0.4064)
			(end 0.7874 0.4064)
			(stroke
				(width 0.1524)
				(type default)
			)
			(layer "F.SilkS")
		)
		(fp_line
			(start -0.7874 0.4064)
			(end -0.7874 -0.4064)
			(stroke
				(width 0.1524)
				(type default)
			)
			(layer "F.SilkS")
		)
		(fp_line
			(start -0.7874 -0.4064)
			(end 0.7874 -0.4064)
			(stroke
				(width 0.1524)
				(type default)
			)
			(layer "F.SilkS")
		)
		(fp_line
			(start 0.67945 0.3048)
			(end 0.120396 0.3048)
			(stroke
				(width 0.1)
				(type default)
			)
			(layer "F.Fab")
		)
		(fp_line
			(start 0.67945 -0.3048)
			(end 0.67945 0.3048)
			(stroke
				(width 0.1)
				(type default)
			)
			(layer "F.Fab")
		)
		(fp_line
			(start 0.12065 -0.2794)
			(end 0.12065 -0.3048)
			(stroke
				(width 0.1)
				(type default)
			)
			(layer "F.Fab")
		)
		(fp_line
			(start 0.12065 -0.3048)
			(end 0.67945 -0.3048)
			(stroke
				(width 0.1)
				(type default)
			)
			(layer "F.Fab")
		)
		(fp_line
			(start 0.120396 0.3048)
			(end 0.120396 0.2794)
			(stroke
				(width 0.1)
				(type default)
			)
			(layer "F.Fab")
		)
		(fp_line
			(start 0.120396 0.2794)
			(end -0.12065 0.2794)
			(stroke
				(width 0.1)
				(type default)
			)
			(layer "F.Fab")
		)
		(fp_line
			(start -0.12065 0.3048)
			(end -0.67945 0.3048)
			(stroke
				(width 0.1)
				(type default)
			)
			(layer "F.Fab")
		)
		(fp_line
			(start -0.12065 0.2794)
			(end -0.12065 0.3048)
			(stroke
				(width 0.1)
				(type default)
			)
			(layer "F.Fab")
		)
		(fp_line
			(start -0.12065 -0.2794)
			(end 0.12065 -0.2794)
			(stroke
				(width 0.1)
				(type default)
			)
			(layer "F.Fab")
		)
		(fp_line
			(start -0.12065 -0.305054)
			(end -0.12065 -0.2794)
			(stroke
				(width 0.1)
				(type default)
			)
			(layer "F.Fab")
		)
		(fp_line
			(start -0.67945 0.3048)
			(end -0.67945 -0.305054)
			(stroke
				(width 0.1)
				(type default)
			)
			(layer "F.Fab")
		)
		(fp_line
			(start -0.67945 -0.305054)
			(end -0.12065 -0.305054)
			(stroke
				(width 0.1)
				(type default)
			)
			(layer "F.Fab")
		)
		(pad "1" smd circle
			(at -0.40005 0 180)
			(size 0 0)
			(layers "F.Cu" "F.Mask" "F.Paste")
			(net "SW_PVDD11_S3_P1_SW2")
		)
		(pad "2" smd circle
			(at 0.40005 0 180)
			(size 0 0)
			(layers "F.Cu" "F.Mask" "F.Paste")
			(net "SW_PVDD11_S3_P1_SW2_RC")
		)
	)
)
